(kicad_pcb
	(version 20260206)
	(generator "pcbnew")
	(generator_version "10.0")
	(general
		(thickness 1.6)
		(legacy_teardrops no)
	)
	(paper "A4")
	(title_block
		(title "Wiwynn_Tioga_Pass_MB.brd")
		(comment 1 "Tioga Pass / footprints 1213-1218 of 4770")
	)
	(layers
		(0 "F.Cu" signal "TOP")
		(4 "In1.Cu" signal "L2GND")
		(6 "In2.Cu" signal "L3")
		(8 "In3.Cu" signal "L4GND")
		(10 "In4.Cu" signal "L5")
		(12 "In5.Cu" signal "L6GND")
		(14 "In6.Cu" signal "L7VCC")
		(16 "In7.Cu" signal "L8VCC")
		(18 "In8.Cu" signal "L9GND")
		(20 "In9.Cu" signal "L10")
		(22 "In10.Cu" signal "L11GND")
		(24 "In11.Cu" signal "L12")
		(26 "In12.Cu" signal "L13GND")
		(2 "B.Cu" signal "BOTTOM")
		(9 "F.Adhes" user "F.Adhesive")
		(11 "B.Adhes" user "B.Adhesive")
		(13 "F.Paste" user "Package Geometry/Pastemask Top")
		(15 "B.Paste" user "Package Geometry/Pastemask Bottom")
		(5 "F.SilkS" user "Ref Des/Silkscreen Top")
		(7 "B.SilkS" user "Ref Des/Silkscreen Bottom")
		(1 "F.Mask" user "Board Geometry/Soldermask Top")
		(3 "B.Mask" user "Board Geometry/Soldermask Bottom")
		(17 "Dwgs.User" user "User.Drawings")
		(19 "Cmts.User" user "User.Comments")
		(21 "Eco1.User" user "User.Eco1")
		(23 "Eco2.User" user "User.Eco2")
		(25 "Edge.Cuts" user "Board Geometry/Outline")
		(27 "Margin" user)
		(31 "F.CrtYd" user "Package Geometry/Place Bound Top")
		(29 "B.CrtYd" user "Package Geometry/Place Bound Bottom")
		(35 "F.Fab" user "Ref Des/Assembly Top")
		(33 "B.Fab" user "Ref Des/Assembly Bottom")
	)
	(footprint ""
		(layer "F.Cu")
		(at 347.462094 -145.293842 -90)
		(property "Reference" "EU7A4"
			(at 5.874512 -1.483106 0)
			(unlocked yes)
			(layer "F.SilkS")
			(effects
				(font
					(size 0.7874 0.5842)
					(thickness 0.1524)
				)
			)
		)
		(property "Value" ""
			(at 0 0 270)
			(layer "F.Fab")
			(effects
				(font
					(size 1.27 1.27)
				)
			)
		)
		(duplicate_pad_numbers_are_jumpers no)
		(fp_line
			(start -3.0099 3.429)
			(end -3.0099 -3.5052)
			(stroke
				(width 0.1524)
				(type default)
			)
			(layer "F.SilkS")
		)
		(fp_line
			(start 2.9718 3.429)
			(end -3.0099 3.429)
			(stroke
				(width 0.1524)
				(type default)
			)
			(layer "F.SilkS")
		)
		(fp_line
			(start -3.0099 -3.5052)
			(end 2.9718 -3.5052)
			(stroke
				(width 0.1524)
				(type default)
			)
			(layer "F.SilkS")
		)
		(fp_line
			(start 2.9718 -3.5052)
			(end 2.9718 3.429)
			(stroke
				(width 0.1524)
				(type default)
			)
			(layer "F.SilkS")
		)
		(fp_circle
			(center -3.736848 -3.271266)
			(end -3.736848 -3.398266)
			(stroke
				(width 0.254)
				(type default)
			)
			(fill no)
			(layer "F.SilkS")
		)
		(fp_poly
			(pts
				(xy -2.9972 -3.4925) (xy -2.9972 -2.6924) (xy -2.1971 -3.4925)
			)
			(stroke
				(width 0)
				(type default)
			)
			(fill yes)
			(layer "F.SilkS")
		)
		(fp_poly
			(pts
				(xy -2.549906 -3.050032) (xy -2.549906 3.050032) (xy 2.549906 3.050032) (xy 2.549906 -3.050032)
			)
			(stroke
				(width 0)
				(type default)
			)
			(fill no)
			(layer "F.CrtYd")
		)
		(fp_line
			(start -2.549906 3.050032)
			(end -2.549906 -3.050032)
			(stroke
				(width 0.1)
				(type default)
			)
			(layer "F.Fab")
		)
		(fp_line
			(start 2.549906 3.050032)
			(end -2.549906 3.050032)
			(stroke
				(width 0.1)
				(type default)
			)
			(layer "F.Fab")
		)
		(fp_line
			(start -2.549906 -3.050032)
			(end 2.549906 -3.050032)
			(stroke
				(width 0.1)
				(type default)
			)
			(layer "F.Fab")
		)
		(fp_line
			(start 2.549906 -3.050032)
			(end 2.549906 3.050032)
			(stroke
				(width 0.1)
				(type default)
			)
			(layer "F.Fab")
		)
		(fp_circle
			(center -3.057398 -2.678684)
			(end -3.057398 -2.805684)
			(stroke
				(width 0.254)
				(type default)
			)
			(fill no)
			(layer "F.Fab")
		)
		(pad "1" smd rect
			(at -2.39522 -2.279904 270)
			(size 0.7112 0.254)
			(layers "F.Cu" "F.Mask" "F.Paste")
			(net "PVDDQ_DEF")
		)
		(pad "2" smd rect
			(at -2.39522 -1.83007 270)
			(size 0.7112 0.254)
			(layers "F.Cu" "F.Mask" "F.Paste")
			(net "GND")
		)
		(pad "3" smd rect
			(at -2.39522 -1.379982 270)
			(size 0.7112 0.254)
			(layers "F.Cu" "F.Mask" "F.Paste")
			(net "VR_PVDDQ_DEF_PH2_VCIN")
		)
		(pad "4" smd rect
			(at -2.39522 -0.929894 270)
			(size 0.7112 0.254)
			(layers "F.Cu" "F.Mask" "F.Paste")
			(net "P5V_STBY")
		)
		(pad "5" smd rect
			(at -2.39522 -0.48006 270)
			(size 0.7112 0.254)
			(layers "F.Cu" "F.Mask" "F.Paste")
			(net "GND")
		)
		(pad "6" smd rect
			(at -2.39522 -0.029972 270)
			(size 0.7112 0.254)
			(layers "F.Cu" "F.Mask" "F.Paste")
			(net "TP_PVDDQ_DEF_PH2_GL_0")
		)
		(pad "7" smd custom
			(at 0.016764 1.145032 270)
			(size 0.53975 0.53975)
			(layers "F.Cu" "F.Mask" "F.Paste")
			(net "GND")
			(options
				(clearance outline)
				(anchor circle)
			)
			(primitives
				(gr_poly
					(pts
						(xy -2.7051 1.0795) (xy -2.7051 -0.3683) (xy -0.9271 -0.3683) (xy -0.9271 -1.0795) (xy 2.7051 -1.0795)
						(xy 2.7051 1.0795)
					)
					(width 0)
					(fill yes)
				)
			)
		)
		(pad "10" smd rect
			(at -0.008382 2.874772 270)
			(size 4.3434 0.6096)
			(layers "F.Cu" "F.Mask" "F.Paste")
			(net "VR_PVDDQ_DEF_PH2_SW")
		)
		(pad "25" smd rect
			(at 1.548384 -1.283208 270)
			(size 2.3368 2.0066)
			(layers "F.Cu" "F.Mask" "F.Paste")
			(net "VR_FET_SW_P12V_STBY_PVDDQ_DEF")
		)
		(pad "30" smd rect
			(at 2.050034 -2.895092 270)
			(size 0.254 0.7112)
			(layers "F.Cu" "F.Mask" "F.Paste")
			(net "VR_FET_SW_P12V_STBY_PVDDQ_DEF")
		)
		(pad "31" smd rect
			(at 1.599946 -2.895092 270)
			(size 0.254 0.7112)
			(layers "F.Cu" "F.Mask" "F.Paste")
			(net "Net_371")
		)
		(pad "32" smd rect
			(at 1.150112 -2.895092 270)
			(size 0.254 0.7112)
			(layers "F.Cu" "F.Mask" "F.Paste")
			(net "VR_PVDDQ_DEF_PH2_PHASE")
		)
		(pad "33" smd rect
			(at 0.700024 -2.895092 270)
			(size 0.254 0.7112)
			(layers "F.Cu" "F.Mask" "F.Paste")
			(net "VR_PVDDQ_DEF_PH2_BOOT_R")
		)
		(pad "34" smd rect
			(at 0.249936 -2.895092 270)
			(size 0.254 0.7112)
			(layers "F.Cu" "F.Mask" "F.Paste")
			(net "VR_PVDDQ_DEF_PWM2")
		)
		(pad "35" smd rect
			(at -0.199898 -2.895092 270)
			(size 0.254 0.7112)
			(layers "F.Cu" "F.Mask" "F.Paste")
			(net "P5V_STBY")
		)
		(pad "36" smd rect
			(at -0.649986 -2.895092 270)
			(size 0.254 0.7112)
			(layers "F.Cu" "F.Mask" "F.Paste")
			(net "A_TSENSE_PVDDQ_DEF")
		)
		(pad "37" smd rect
			(at -1.100074 -2.895092 270)
			(size 0.254 0.7112)
			(layers "F.Cu" "F.Mask" "F.Paste")
			(net "VR_PVDDQ_DEF_PH2_OCSET")
		)
		(pad "38" smd rect
			(at -1.549908 -2.895092 270)
			(size 0.254 0.7112)
			(layers "F.Cu" "F.Mask" "F.Paste")
			(net "ISENSE_PVDDQ_DEF_PH2_IMON")
		)
		(pad "39" smd rect
			(at -1.999996 -2.895092 270)
			(size 0.254 0.7112)
			(layers "F.Cu" "F.Mask" "F.Paste")
			(net "VR_PVDDQ_DEF_AIREF2")
		)
		(pad "40" smd rect
			(at -0.871728 -1.283208 270)
			(size 1.8034 2.0066)
			(layers "F.Cu" "F.Mask" "F.Paste")
			(net "GND")
		)
		(pad "41" smd rect
			(at -1.533906 0.247904 270)
			(size 0.508 0.3556)
			(layers "F.Cu" "F.Mask" "F.Paste")
			(net "TP_PVDDQ_DEF_PH2_GL_1")
		)
	)
	(footprint ""
		(layer "F.Cu")
		(at 405.283416 -148.436584 90)
		(property "Reference" "C8A11"
			(at 0 0 90)
			(layer "F.SilkS")
			(hide yes)
			(effects
				(font
					(size 1.27 1.27)
				)
			)
		)
		(property "Value" ""
			(at 0 0 90)
			(layer "F.Fab")
			(effects
				(font
					(size 1.27 1.27)
				)
			)
		)
		(duplicate_pad_numbers_are_jumpers no)
		(fp_poly
			(pts
				(xy 0.3048 -0.1016) (xy 0.3048 0.9906) (xy -0.3048 0.9906) (xy -0.3048 -0.1016)
			)
			(stroke
				(width 0)
				(type default)
			)
			(fill no)
			(layer "F.CrtYd")
		)
		(fp_line
			(start 0.3048 -0.1016)
			(end -0.3048 -0.1016)
			(stroke
				(width 0.1)
				(type default)
			)
			(layer "F.Fab")
		)
		(fp_line
			(start -0.3048 -0.1016)
			(end -0.3048 0.9906)
			(stroke
				(width 0.1)
				(type default)
			)
			(layer "F.Fab")
		)
		(fp_line
			(start 0.3048 0.9906)
			(end 0.3048 -0.1016)
			(stroke
				(width 0.1)
				(type default)
			)
			(layer "F.Fab")
		)
		(fp_line
			(start -0.3048 0.9906)
			(end 0.3048 0.9906)
			(stroke
				(width 0.1)
				(type default)
			)
			(layer "F.Fab")
		)
		(pad "1" smd rect
			(at 0 0 90)
			(size 0.508 0.508)
			(layers "F.Cu" "F.Mask" "F.Paste")
			(net "PWRGD_P1V8_PCH_STBY_R")
		)
		(pad "2" smd rect
			(at 0 0.889 90)
			(size 0.508 0.508)
			(layers "F.Cu" "F.Mask" "F.Paste")
			(net "GND")
		)
		(zone
			(layer "F.Cu")
			(hatch none 0.5)
			(connect_pads
				(clearance 0)
			)
			(min_thickness 0.25)
			(keepout
				(tracks allowed)
				(vias not_allowed)
				(pads allowed)
				(copperpour not_allowed)
				(footprints allowed)
			)
			(placement
				(enabled no)
				(sheetname "")
			)
			(fill
				(thermal_gap 0.5)
				(thermal_bridge_width 0.5)
				(island_removal_mode 0)
			)
			(polygon
				(pts
					(xy 405.537416 -148.182584) (xy 405.537416 -148.690584) (xy 405.918416 -148.690584) (xy 405.918416 -148.182584)
				)
			)
		)
		(zone
			(layer "F.Cu")
			(hatch none 0.5)
			(connect_pads
				(clearance 0)
			)
			(min_thickness 0.25)
			(keepout
				(tracks not_allowed)
				(vias allowed)
				(pads allowed)
				(copperpour not_allowed)
				(footprints allowed)
			)
			(placement
				(enabled no)
				(sheetname "")
			)
			(fill
				(thermal_gap 0.5)
				(thermal_bridge_width 0.5)
				(island_removal_mode 0)
			)
			(polygon
				(pts
					(xy 405.918416 -148.182584) (xy 405.918416 -148.690584) (xy 405.537416 -148.690584) (xy 405.537416 -148.182584)
				)
			)
		)
	)
	(footprint ""
		(layer "F.Cu")
		(at 429.220122 -45.054774 90)
		(property "Reference" "R9F60"
			(at 0 0 90)
			(layer "F.SilkS")
			(hide yes)
			(effects
				(font
					(size 1.27 1.27)
				)
			)
		)
		(property "Value" ""
			(at 0 0 90)
			(layer "F.Fab")
			(effects
				(font
					(size 1.27 1.27)
				)
			)
		)
		(duplicate_pad_numbers_are_jumpers no)
		(fp_poly
			(pts
				(xy -0.2794 -0.1016) (xy 0.2794 -0.1016) (xy 0.2794 0.9906) (xy -0.2794 0.9906)
			)
			(stroke
				(width 0)
				(type default)
			)
			(fill no)
			(layer "F.CrtYd")
		)
		(fp_line
			(start 0.2794 -0.1016)
			(end -0.2794 -0.1016)
			(stroke
				(width 0.1)
				(type default)
			)
			(layer "F.Fab")
		)
		(fp_line
			(start -0.2794 -0.1016)
			(end -0.2794 0.9906)
			(stroke
				(width 0.1)
				(type default)
			)
			(layer "F.Fab")
		)
		(fp_line
			(start 0.2794 0.9906)
			(end 0.2794 -0.1016)
			(stroke
				(width 0.1)
				(type default)
			)
			(layer "F.Fab")
		)
		(fp_line
			(start -0.2794 0.9906)
			(end 0.2794 0.9906)
			(stroke
				(width 0.1)
				(type default)
			)
			(layer "F.Fab")
		)
		(pad "1" smd rect
			(at 0 0 90)
			(size 0.508 0.508)
			(layers "F.Cu" "F.Mask" "F.Paste")
			(net "CLK_25M_BMC")
		)
		(pad "2" smd rect
			(at 0 0.889 90)
			(size 0.508 0.508)
			(layers "F.Cu" "F.Mask" "F.Paste")
			(net "CLK_24M_25M_BMC_CLKIN")
		)
		(zone
			(layer "F.Cu")
			(hatch none 0.5)
			(connect_pads
				(clearance 0)
			)
			(min_thickness 0.25)
			(keepout
				(tracks allowed)
				(vias not_allowed)
				(pads allowed)
				(copperpour not_allowed)
				(footprints allowed)
			)
			(placement
				(enabled no)
				(sheetname "")
			)
			(fill
				(thermal_gap 0.5)
				(thermal_bridge_width 0.5)
				(island_removal_mode 0)
			)
			(polygon
				(pts
					(xy 429.474122 -44.800774) (xy 429.474122 -45.308774) (xy 429.855122 -45.308774) (xy 429.855122 -44.800774)
				)
			)
		)
		(zone
			(layer "F.Cu")
			(hatch none 0.5)
			(connect_pads
				(clearance 0)
			)
			(min_thickness 0.25)
			(keepout
				(tracks not_allowed)
				(vias allowed)
				(pads allowed)
				(copperpour not_allowed)
				(footprints allowed)
			)
			(placement
				(enabled no)
				(sheetname "")
			)
			(fill
				(thermal_gap 0.5)
				(thermal_bridge_width 0.5)
				(island_removal_mode 0)
			)
			(polygon
				(pts
					(xy 429.855122 -44.800774) (xy 429.855122 -45.308774) (xy 429.474122 -45.308774) (xy 429.474122 -44.800774)
				)
			)
		)
	)
	(footprint ""
		(layer "F.Cu")
		(at 475.7801 -141.6177 180)
		(property "Reference" "C1L17"
			(at 0 0 180)
			(layer "F.SilkS")
			(hide yes)
			(effects
				(font
					(size 1.27 1.27)
				)
			)
		)
		(property "Value" ""
			(at 0 0 180)
			(layer "F.Fab")
			(effects
				(font
					(size 1.27 1.27)
				)
			)
		)
		(duplicate_pad_numbers_are_jumpers no)
		(fp_poly
			(pts
				(xy 0.3048 -0.1016) (xy 0.3048 0.9906) (xy -0.3048 0.9906) (xy -0.3048 -0.1016)
			)
			(stroke
				(width 0)
				(type default)
			)
			(fill no)
			(layer "F.CrtYd")
		)
		(fp_line
			(start 0.3048 0.9906)
			(end 0.3048 -0.1016)
			(stroke
				(width 0.1)
				(type default)
			)
			(layer "F.Fab")
		)
		(fp_line
			(start 0.3048 -0.1016)
			(end -0.3048 -0.1016)
			(stroke
				(width 0.1)
				(type default)
			)
			(layer "F.Fab")
		)
		(fp_line
			(start -0.3048 0.9906)
			(end 0.3048 0.9906)
			(stroke
				(width 0.1)
				(type default)
			)
			(layer "F.Fab")
		)
		(fp_line
			(start -0.3048 -0.1016)
			(end -0.3048 0.9906)
			(stroke
				(width 0.1)
				(type default)
			)
			(layer "F.Fab")
		)
		(pad "1" smd rect
			(at 0 0 180)
			(size 0.508 0.508)
			(layers "F.Cu" "F.Mask" "F.Paste")
			(net "P3V3_STBY")
		)
		(pad "2" smd rect
			(at 0 0.889 180)
			(size 0.508 0.508)
			(layers "F.Cu" "F.Mask" "F.Paste")
			(net "GND")
		)
		(zone
			(layer "F.Cu")
			(hatch none 0.5)
			(connect_pads
				(clearance 0)
			)
			(min_thickness 0.25)
			(keepout
				(tracks not_allowed)
				(vias allowed)
				(pads allowed)
				(copperpour not_allowed)
				(footprints allowed)
			)
			(placement
				(enabled no)
				(sheetname "")
			)
			(fill
				(thermal_gap 0.5)
				(thermal_bridge_width 0.5)
				(island_removal_mode 0)
			)
			(polygon
				(pts
					(xy 476.0341 -142.2527) (xy 475.5261 -142.2527) (xy 475.5261 -141.8717) (xy 476.0341 -141.8717)
				)
			)
		)
		(zone
			(layer "F.Cu")
			(hatch none 0.5)
			(connect_pads
				(clearance 0)
			)
			(min_thickness 0.25)
			(keepout
				(tracks allowed)
				(vias not_allowed)
				(pads allowed)
				(copperpour not_allowed)
				(footprints allowed)
			)
			(placement
				(enabled no)
				(sheetname "")
			)
			(fill
				(thermal_gap 0.5)
				(thermal_bridge_width 0.5)
				(island_removal_mode 0)
			)
			(polygon
				(pts
					(xy 476.0341 -141.8717) (xy 475.5261 -141.8717) (xy 475.5261 -142.2527) (xy 476.0341 -142.2527)
				)
			)
		)
	)
	(footprint ""
		(layer "F.Cu")
		(at 351.663 -135.001)
		(property "Reference" "FB7B1"
			(at 0 0 0)
			(layer "F.SilkS")
			(hide yes)
			(effects
				(font
					(size 1.27 1.27)
				)
			)
		)
		(property "Value" ""
			(at 0 0 0)
			(layer "F.Fab")
			(effects
				(font
					(size 1.27 1.27)
				)
			)
		)
		(duplicate_pad_numbers_are_jumpers no)
		(fp_poly
			(pts
				(xy -0.7239 -0.26035) (xy 0.7239 -0.26035) (xy 0.7239 2.03835) (xy -0.7239 2.03835)
			)
			(stroke
				(width 0)
				(type default)
			)
			(fill no)
			(layer "F.CrtYd")
		)
		(fp_line
			(start -0.7239 -0.26035)
			(end 0.7239 -0.26035)
			(stroke
				(width 0.1)
				(type default)
			)
			(layer "F.Fab")
		)
		(fp_line
			(start -0.7239 2.03835)
			(end -0.7239 -0.26035)
			(stroke
				(width 0.1)
				(type default)
			)
			(layer "F.Fab")
		)
		(fp_line
			(start 0.7239 -0.26035)
			(end 0.7239 2.03835)
			(stroke
				(width 0.1)
				(type default)
			)
			(layer "F.Fab")
		)
		(fp_line
			(start 0.7239 2.03835)
			(end -0.7239 2.03835)
			(stroke
				(width 0.1)
				(type default)
			)
			(layer "F.Fab")
		)
		(pad "1" smd rect
			(at 0 0)
			(size 1.27 1.016)
			(layers "F.Cu" "F.Mask" "F.Paste")
			(net "P12V_STBY")
		)
		(pad "2" smd rect
			(at 0 1.778)
			(size 1.27 1.016)
			(layers "F.Cu" "F.Mask" "F.Paste")
			(net "VR_FET_SW_P12V_STBY_PVPP_DEF")
		)
		(zone
			(layer "F.Cu")
			(hatch none 0.5)
			(connect_pads
				(clearance 0)
			)
			(min_thickness 0.25)
			(keepout
				(tracks not_allowed)
				(vias allowed)
				(pads allowed)
				(copperpour not_allowed)
				(footprints allowed)
			)
			(placement
				(enabled no)
				(sheetname "")
			)
			(fill
				(thermal_gap 0.5)
				(thermal_bridge_width 0.5)
				(island_removal_mode 0)
			)
			(polygon
				(pts
					(xy 352.298 -134.493) (xy 352.298 -133.731) (xy 352.2091 -133.731) (xy 351.028 -133.731) (xy 351.028 -134.493)
				)
			)
		)
	)
	(footprint ""
		(layer "F.Cu")
		(at 432.6509 -45.1739)
		(property "Reference" "R25W95"
			(at -0.8382 -0.67818 0)
			(unlocked yes)
			(layer "F.SilkS")
			(effects
				(font
					(size 0.4064 0.254)
					(thickness 0.1524)
				)
				(justify left)
			)
		)
		(property "Value" ""
			(at 0 0 0)
			(layer "F.Fab")
			(effects
				(font
					(size 1.27 1.27)
				)
			)
		)
		(duplicate_pad_numbers_are_jumpers no)
		(fp_poly
			(pts
				(xy -0.2794 -0.1016) (xy 0.2794 -0.1016) (xy 0.2794 0.9906) (xy -0.2794 0.9906)
			)
			(stroke
				(width 0)
				(type default)
			)
			(fill no)
			(layer "F.CrtYd")
		)
		(fp_line
			(start -0.2794 -0.1016)
			(end -0.2794 0.9906)
			(stroke
				(width 0.1)
				(type default)
			)
			(layer "F.Fab")
		)
		(fp_line
			(start -0.2794 0.9906)
			(end 0.2794 0.9906)
			(stroke
				(width 0.1)
				(type default)
			)
			(layer "F.Fab")
		)
		(fp_line
			(start 0.2794 -0.1016)
			(end -0.2794 -0.1016)
			(stroke
				(width 0.1)
				(type default)
			)
			(layer "F.Fab")
		)
		(fp_line
			(start 0.2794 0.9906)
			(end 0.2794 -0.1016)
			(stroke
				(width 0.1)
				(type default)
			)
			(layer "F.Fab")
		)
		(pad "1" smd rect
			(at 0 0)
			(size 0.508 0.508)
			(layers "F.Cu" "F.Mask" "F.Paste")
			(net "P3V3_STBY")
		)
		(pad "2" smd rect
			(at 0 0.889)
			(size 0.508 0.508)
			(layers "F.Cu" "F.Mask" "F.Paste")
			(net "SPI_BMC_BT_CLK")
		)
		(zone
			(layer "F.Cu")
			(hatch none 0.5)
			(connect_pads
				(clearance 0)
			)
			(min_thickness 0.25)
			(keepout
				(tracks allowed)
				(vias not_allowed)
				(pads allowed)
				(copperpour not_allowed)
				(footprints allowed)
			)
			(placement
				(enabled no)
				(sheetname "")
			)
			(fill
				(thermal_gap 0.5)
				(thermal_bridge_width 0.5)
				(island_removal_mode 0)
			)
			(polygon
				(pts
					(xy 432.3969 -44.9199) (xy 432.9049 -44.9199) (xy 432.9049 -44.5389) (xy 432.3969 -44.5389)
				)
			)
		)
		(zone
			(layer "F.Cu")
			(hatch none 0.5)
			(connect_pads
				(clearance 0)
			)
			(min_thickness 0.25)
			(keepout
				(tracks not_allowed)
				(vias allowed)
				(pads allowed)
				(copperpour not_allowed)
				(footprints allowed)
			)
			(placement
				(enabled no)
				(sheetname "")
			)
			(fill
				(thermal_gap 0.5)
				(thermal_bridge_width 0.5)
				(island_removal_mode 0)
			)
			(polygon
				(pts
					(xy 432.3969 -44.5389) (xy 432.9049 -44.5389) (xy 432.9049 -44.9199) (xy 432.3969 -44.9199)
				)
			)
		)
	)
)
